# T6G (Grand Teton) — schematic netlist excerpt (pin names and nets, part order shuffled) for the footprints in the layout excerpt that follows; sources: Cadence DE-HDL packaged netlist, KiCad conversion of 04192023_DAF0TMB3IC0_F0TG_MB_C_brd_V02_OCP.brd

C867  Q_CAP_DIFFBUS  DIFF BUS_0.22UF 6.3V 20% X6S  pkg C0201  page 64 : \1\ = P5E_CPU0_P2_TX_C_DP<1> ; \2\ = P5E_CPU0_P2_TX_DP<1>
H105  HOLE  EMPTY  pkg TH  page 230 : \1\ = GND
PC6514  Q_CAP  0.1UF 25V 10% X7R  pkg 0402  page 360 : A = P1V8_CPU0_RT_1D ; B = GND
C2161  Q_CAP  22UF 4V 20% X6S  pkg C0402  page 68 : A = PVDDCR_SOC_P0 ; B = GND

(kicad_pcb
	(version 20260206)
	(generator "pcbnew")
	(generator_version "10.0")
	(general
		(thickness 1.6)
		(legacy_teardrops no)
	)
	(paper "A4")
	(title_block
		(title "04192023_DAF0TMB3IC0_F0TG_MB_C_brd_V02_OCP.brd")
		(comment 1 "Grand Teton / footprints 4745-4748 of 8354")
	)
	(layers
		(0 "F.Cu" signal "TOP")
		(4 "In1.Cu" signal "GND")
		(6 "In2.Cu" signal "IN1")
		(8 "In3.Cu" signal "GND1")
		(10 "In4.Cu" signal "IN2")
		(12 "In5.Cu" signal "GND2")
		(14 "In6.Cu" signal "IN3")
		(16 "In7.Cu" signal "GND3")
		(18 "In8.Cu" signal "VCC")
		(20 "In9.Cu" signal "VCC1")
		(22 "In10.Cu" signal "GND4")
		(24 "In11.Cu" signal "IN4")
		(26 "In12.Cu" signal "GND5")
		(28 "In13.Cu" signal "IN5")
		(30 "In14.Cu" signal "GND6")
		(32 "In15.Cu" signal "IN6")
		(34 "In16.Cu" signal "GND7")
		(2 "B.Cu" signal "BOTTOM")
		(9 "F.Adhes" user "F.Adhesive")
		(11 "B.Adhes" user "B.Adhesive")
		(13 "F.Paste" user "Package Geometry/Pastemask Top")
		(15 "B.Paste" user "Package Geometry/Pastemask Bottom")
		(5 "F.SilkS" user "Ref Des/Silkscreen Top")
		(7 "B.SilkS" user "Ref Des/Silkscreen Bottom")
		(1 "F.Mask" user "Board Geometry/Soldermask Top")
		(3 "B.Mask" user "Board Geometry/Soldermask Bottom")
		(17 "Dwgs.User" user "User.Drawings")
		(19 "Cmts.User" user "User.Comments")
		(21 "Eco1.User" user "User.Eco1")
		(23 "Eco2.User" user "User.Eco2")
		(25 "Edge.Cuts" user "Board Geometry/Outline")
		(27 "Margin" user)
		(31 "F.CrtYd" user "Package Geometry/Place Bound Top")
		(29 "B.CrtYd" user "Package Geometry/Place Bound Bottom")
		(35 "F.Fab" user "Ref Des/Assembly Top")
		(33 "B.Fab" user "Ref Des/Assembly Bottom")
	)
	(footprint ""
		(layer "F.Cu")
		(at 398.595088 -384.32486 180)
		(property "Reference" "C867"
			(at 0 0 180)
			(layer "F.SilkS")
			(hide yes)
			(effects
				(font
					(size 1.27 1.27)
				)
			)
		)
		(property "Value" ""
			(at 0 0 180)
			(layer "F.Fab")
			(effects
				(font
					(size 1.27 1.27)
				)
			)
		)
		(duplicate_pad_numbers_are_jumpers no)
		(fp_line
			(start 0.299974 0.150114)
			(end -0.299974 0.150114)
			(stroke
				(width 0.1)
				(type default)
			)
			(layer "F.Fab")
		)
		(fp_line
			(start 0.299974 -0.150114)
			(end 0.299974 0.150114)
			(stroke
				(width 0.1)
				(type default)
			)
			(layer "F.Fab")
		)
		(fp_line
			(start -0.299974 0.150114)
			(end -0.299974 -0.150114)
			(stroke
				(width 0.1)
				(type default)
			)
			(layer "F.Fab")
		)
		(fp_line
			(start -0.299974 -0.150114)
			(end 0.299974 -0.150114)
			(stroke
				(width 0.1)
				(type default)
			)
			(layer "F.Fab")
		)
		(pad "1" smd rect
			(at -0.2667 0 180)
			(size 0.3048 0.381)
			(layers "F.Cu" "F.Mask" "F.Paste")
			(net "P5E_CPU0_P2_TX_C_DP<1>")
		)
		(pad "2" smd rect
			(at 0.2667 0 180)
			(size 0.3048 0.381)
			(layers "F.Cu" "F.Mask" "F.Paste")
			(net "P5E_CPU0_P2_TX_DP<1>")
		)
	)
	(footprint ""
		(layer "F.Cu")
		(at 236.650022 -352.49993)
		(property "Reference" "H105"
			(at -5.01269 -6.23189 0)
			(unlocked yes)
			(layer "F.SilkS")
			(effects
				(font
					(size 0.7874 0.5842)
					(thickness 0.1524)
				)
				(justify left)
			)
		)
		(property "Value" ""
			(at 0 0 0)
			(layer "F.Fab")
			(effects
				(font
					(size 1.27 1.27)
				)
			)
		)
		(duplicate_pad_numbers_are_jumpers no)
		(pad "1" thru_hole circle
			(at 0 0)
			(size 10.0076 10.0076)
			(drill 5.6134)
			(layers "*.Cu" "*.Mask")
			(remove_unused_layers no)
			(net "GND")
			(clearance -1.9431)
		)
	)
	(footprint ""
		(layer "F.Cu")
		(at 237.720378 -315.95568 90)
		(property "Reference" "PC6514"
			(at 0 0 90)
			(layer "F.SilkS")
			(hide yes)
			(effects
				(font
					(size 1.27 1.27)
				)
			)
		)
		(property "Value" ""
			(at 0 0 90)
			(layer "F.Fab")
			(effects
				(font
					(size 1.27 1.27)
				)
			)
		)
		(duplicate_pad_numbers_are_jumpers no)
		(fp_line
			(start 0.7874 -0.4064)
			(end 0.7874 0.4064)
			(stroke
				(width 0.1524)
				(type default)
			)
			(layer "F.SilkS")
		)
		(fp_line
			(start -0.7874 -0.4064)
			(end 0.7874 -0.4064)
			(stroke
				(width 0.1524)
				(type default)
			)
			(layer "F.SilkS")
		)
		(fp_line
			(start 0.7874 0.4064)
			(end -0.7874 0.4064)
			(stroke
				(width 0.1524)
				(type default)
			)
			(layer "F.SilkS")
		)
		(fp_line
			(start -0.7874 0.4064)
			(end -0.7874 -0.4064)
			(stroke
				(width 0.1524)
				(type default)
			)
			(layer "F.SilkS")
		)
		(fp_line
			(start -0.12065 -0.305054)
			(end -0.12065 -0.2794)
			(stroke
				(width 0.1)
				(type default)
			)
			(layer "F.Fab")
		)
		(fp_line
			(start -0.67945 -0.305054)
			(end -0.12065 -0.305054)
			(stroke
				(width 0.1)
				(type default)
			)
			(layer "F.Fab")
		)
		(fp_line
			(start 0.67945 -0.3048)
			(end 0.67945 0.3048)
			(stroke
				(width 0.1)
				(type default)
			)
			(layer "F.Fab")
		)
		(fp_line
			(start 0.12065 -0.3048)
			(end 0.67945 -0.3048)
			(stroke
				(width 0.1)
				(type default)
			)
			(layer "F.Fab")
		)
		(fp_line
			(start 0.12065 -0.2794)
			(end 0.12065 -0.3048)
			(stroke
				(width 0.1)
				(type default)
			)
			(layer "F.Fab")
		)
		(fp_line
			(start -0.12065 -0.2794)
			(end 0.12065 -0.2794)
			(stroke
				(width 0.1)
				(type default)
			)
			(layer "F.Fab")
		)
		(fp_line
			(start 0.120396 0.2794)
			(end -0.12065 0.2794)
			(stroke
				(width 0.1)
				(type default)
			)
			(layer "F.Fab")
		)
		(fp_line
			(start -0.12065 0.2794)
			(end -0.12065 0.3048)
			(stroke
				(width 0.1)
				(type default)
			)
			(layer "F.Fab")
		)
		(fp_line
			(start 0.67945 0.3048)
			(end 0.120396 0.3048)
			(stroke
				(width 0.1)
				(type default)
			)
			(layer "F.Fab")
		)
		(fp_line
			(start 0.120396 0.3048)
			(end 0.120396 0.2794)
			(stroke
				(width 0.1)
				(type default)
			)
			(layer "F.Fab")
		)
		(fp_line
			(start -0.12065 0.3048)
			(end -0.67945 0.3048)
			(stroke
				(width 0.1)
				(type default)
			)
			(layer "F.Fab")
		)
		(fp_line
			(start -0.67945 0.3048)
			(end -0.67945 -0.305054)
			(stroke
				(width 0.1)
				(type default)
			)
			(layer "F.Fab")
		)
		(pad "1" smd circle
			(at -0.40005 0 90)
			(size 0 0)
			(layers "F.Cu" "F.Mask" "F.Paste")
			(net "P1V8_CPU0_RT_1D")
		)
		(pad "2" smd circle
			(at 0.40005 0 90)
			(size 0 0)
			(layers "F.Cu" "F.Mask" "F.Paste")
			(net "GND")
		)
	)
	(footprint ""
		(layer "F.Cu")
		(at 363.215936 -256.012188 90)
		(property "Reference" "C2161"
			(at 0 0 90)
			(layer "F.SilkS")
			(hide yes)
			(effects
				(font
					(size 1.27 1.27)
				)
			)
		)
		(property "Value" ""
			(at 0 0 90)
			(layer "F.Fab")
			(effects
				(font
					(size 1.27 1.27)
				)
			)
		)
		(duplicate_pad_numbers_are_jumpers no)
		(fp_line
			(start 0.7874 -0.4064)
			(end 0.7874 0.4064)
			(stroke
				(width 0.1524)
				(type default)
			)
			(layer "F.SilkS")
		)
		(fp_line
			(start -0.7874 -0.4064)
			(end 0.7874 -0.4064)
			(stroke
				(width 0.1524)
				(type default)
			)
			(layer "F.SilkS")
		)
		(fp_line
			(start 0.7874 0.4064)
			(end -0.7874 0.4064)
			(stroke
				(width 0.1524)
				(type default)
			)
			(layer "F.SilkS")
		)
		(fp_line
			(start -0.7874 0.4064)
			(end -0.7874 -0.4064)
			(stroke
				(width 0.1524)
				(type default)
			)
			(layer "F.SilkS")
		)
		(fp_line
			(start -0.12065 -0.305054)
			(end -0.12065 -0.2794)
			(stroke
				(width 0.1)
				(type default)
			)
			(layer "F.Fab")
		)
		(fp_line
			(start -0.67945 -0.305054)
			(end -0.12065 -0.305054)
			(stroke
				(width 0.1)
				(type default)
			)
			(layer "F.Fab")
		)
		(fp_line
			(start 0.67945 -0.3048)
			(end 0.67945 0.3048)
			(stroke
				(width 0.1)
				(type default)
			)
			(layer "F.Fab")
		)
		(fp_line
			(start 0.12065 -0.3048)
			(end 0.67945 -0.3048)
			(stroke
				(width 0.1)
				(type default)
			)
			(layer "F.Fab")
		)
		(fp_line
			(start 0.12065 -0.2794)
			(end 0.12065 -0.3048)
			(stroke
				(width 0.1)
				(type default)
			)
			(layer "F.Fab")
		)
		(fp_line
			(start -0.12065 -0.2794)
			(end 0.12065 -0.2794)
			(stroke
				(width 0.1)
				(type default)
			)
			(layer "F.Fab")
		)
		(fp_line
			(start 0.120396 0.2794)
			(end -0.12065 0.2794)
			(stroke
				(width 0.1)
				(type default)
			)
			(layer "F.Fab")
		)
		(fp_line
			(start -0.12065 0.2794)
			(end -0.12065 0.3048)
			(stroke
				(width 0.1)
				(type default)
			)
			(layer "F.Fab")
		)
		(fp_line
			(start 0.67945 0.3048)
			(end 0.120396 0.3048)
			(stroke
				(width 0.1)
				(type default)
			)
			(layer "F.Fab")
		)
		(fp_line
			(start 0.120396 0.3048)
			(end 0.120396 0.2794)
			(stroke
				(width 0.1)
				(type default)
			)
			(layer "F.Fab")
		)
		(fp_line
			(start -0.12065 0.3048)
			(end -0.67945 0.3048)
			(stroke
				(width 0.1)
				(type default)
			)
			(layer "F.Fab")
		)
		(fp_line
			(start -0.67945 0.3048)
			(end -0.67945 -0.305054)
			(stroke
				(width 0.1)
				(type default)
			)
			(layer "F.Fab")
		)
		(pad "1" smd circle
			(at -0.40005 0 90)
			(size 0 0)
			(layers "F.Cu" "F.Mask" "F.Paste")
			(net "PVDDCR_SOC_P0")
		)
		(pad "2" smd circle
			(at 0.40005 0 90)
			(size 0 0)
			(layers "F.Cu" "F.Mask" "F.Paste")
			(net "GND")
		)
	)
)
